# S9S_MB_2U (Grand Teton) — schematic netlist excerpt (pin names and nets, part order shuffled) for the footprints in the layout excerpt that follows; sources: Cadence DE-HDL packaged netlist, KiCad conversion of 03242023_DA0F0TMBIJ0_F0T_Motherboard_J_brd_V01_OCP.brd

R4068  Q_RES  10K 1% EMPTY  pkg 0402LF  page 156 : A = P12V_AUX ; B = P12V_OCP_1_EN_G

(kicad_pcb
	(version 20260206)
	(generator "pcbnew")
	(generator_version "10.0")
	(general
		(thickness 1.6)
		(legacy_teardrops no)
	)
	(paper "A4")
	(title_block
		(title "03242023_DA0F0TMBIJ0_F0T_Motherboard_J_brd_V01_OCP.brd")
		(comment 1 "Grand Teton / footprints 2141-2141 of 6105")
	)
	(layers
		(0 "F.Cu" signal "TOP")
		(4 "In1.Cu" signal "GND")
		(6 "In2.Cu" signal "IN1")
		(8 "In3.Cu" signal "GND1")
		(10 "In4.Cu" signal "IN2")
		(12 "In5.Cu" signal "GND2")
		(14 "In6.Cu" signal "IN3")
		(16 "In7.Cu" signal "GND3")
		(18 "In8.Cu" signal "VCC")
		(20 "In9.Cu" signal "VCC1")
		(22 "In10.Cu" signal "GND4")
		(24 "In11.Cu" signal "IN4")
		(26 "In12.Cu" signal "GND5")
		(28 "In13.Cu" signal "IN5")
		(30 "In14.Cu" signal "GND6")
		(32 "In15.Cu" signal "IN6")
		(34 "In16.Cu" signal "GND7")
		(2 "B.Cu" signal "BOTTOM")
		(9 "F.Adhes" user "F.Adhesive")
		(11 "B.Adhes" user "B.Adhesive")
		(13 "F.Paste" user "Package Geometry/Pastemask Top")
		(15 "B.Paste" user "Package Geometry/Pastemask Bottom")
		(5 "F.SilkS" user "Ref Des/Silkscreen Top")
		(7 "B.SilkS" user "Ref Des/Silkscreen Bottom")
		(1 "F.Mask" user "Board Geometry/Soldermask Top")
		(3 "B.Mask" user "Board Geometry/Soldermask Bottom")
		(17 "Dwgs.User" user "User.Drawings")
		(19 "Cmts.User" user "User.Comments")
		(21 "Eco1.User" user "User.Eco1")
		(23 "Eco2.User" user "User.Eco2")
		(25 "Edge.Cuts" user "Board Geometry/Outline")
		(27 "Margin" user)
		(31 "F.CrtYd" user "Package Geometry/Place Bound Top")
		(29 "B.CrtYd" user "Package Geometry/Place Bound Bottom")
		(35 "F.Fab" user "Ref Des/Assembly Top")
		(33 "B.Fab" user "Ref Des/Assembly Bottom")
	)
	(footprint ""
		(layer "F.Cu")
		(at 469.694514 -41.87825 -90)
		(property "Reference" "R4068"
			(at 0 0 270)
			(layer "F.SilkS")
			(hide yes)
			(effects
				(font
					(size 1.27 1.27)
				)
			)
		)
		(property "Value" ""
			(at 0 0 270)
			(layer "F.Fab")
			(effects
				(font
					(size 1.27 1.27)
				)
			)
		)
		(duplicate_pad_numbers_are_jumpers no)
		(fp_line
			(start -0.7874 0.4064)
			(end -0.7874 -0.4064)
			(stroke
				(width 0.1524)
				(type default)
			)
			(layer "F.SilkS")
		)
		(fp_line
			(start 0.7874 0.4064)
			(end -0.7874 0.4064)
			(stroke
				(width 0.1524)
				(type default)
			)
			(layer "F.SilkS")
		)
		(fp_line
			(start -0.7874 -0.4064)
			(end 0.7874 -0.4064)
			(stroke
				(width 0.1524)
				(type default)
			)
			(layer "F.SilkS")
		)
		(fp_line
			(start 0.7874 -0.4064)
			(end 0.7874 0.4064)
			(stroke
				(width 0.1524)
				(type default)
			)
			(layer "F.SilkS")
		)
		(fp_line
			(start -0.67945 0.3048)
			(end -0.67945 -0.305054)
			(stroke
				(width 0.1)
				(type default)
			)
			(layer "F.Fab")
		)
		(fp_line
			(start -0.12065 0.3048)
			(end -0.67945 0.3048)
			(stroke
				(width 0.1)
				(type default)
			)
			(layer "F.Fab")
		)
		(fp_line
			(start 0.120396 0.3048)
			(end 0.120396 0.2794)
			(stroke
				(width 0.1)
				(type default)
			)
			(layer "F.Fab")
		)
		(fp_line
			(start 0.67945 0.3048)
			(end 0.120396 0.3048)
			(stroke
				(width 0.1)
				(type default)
			)
			(layer "F.Fab")
		)
		(fp_line
			(start -0.12065 0.2794)
			(end -0.12065 0.3048)
			(stroke
				(width 0.1)
				(type default)
			)
			(layer "F.Fab")
		)
		(fp_line
			(start 0.120396 0.2794)
			(end -0.12065 0.2794)
			(stroke
				(width 0.1)
				(type default)
			)
			(layer "F.Fab")
		)
		(fp_line
			(start -0.12065 -0.2794)
			(end 0.12065 -0.2794)
			(stroke
				(width 0.1)
				(type default)
			)
			(layer "F.Fab")
		)
		(fp_line
			(start 0.12065 -0.2794)
			(end 0.12065 -0.3048)
			(stroke
				(width 0.1)
				(type default)
			)
			(layer "F.Fab")
		)
		(fp_line
			(start 0.12065 -0.3048)
			(end 0.67945 -0.3048)
			(stroke
				(width 0.1)
				(type default)
			)
			(layer "F.Fab")
		)
		(fp_line
			(start 0.67945 -0.3048)
			(end 0.67945 0.3048)
			(stroke
				(width 0.1)
				(type default)
			)
			(layer "F.Fab")
		)
		(fp_line
			(start -0.67945 -0.305054)
			(end -0.12065 -0.305054)
			(stroke
				(width 0.1)
				(type default)
			)
			(layer "F.Fab")
		)
		(fp_line
			(start -0.12065 -0.305054)
			(end -0.12065 -0.2794)
			(stroke
				(width 0.1)
				(type default)
			)
			(layer "F.Fab")
		)
		(pad "1" smd circle
			(at -0.40005 0 270)
			(size 0 0)
			(layers "F.Cu" "F.Mask" "F.Paste")
			(net "P12V_AUX")
		)
		(pad "2" smd circle
			(at 0.40005 0 270)
			(size 0 0)
			(layers "F.Cu" "F.Mask" "F.Paste")
			(net "P12V_OCP_1_EN_G")
		)
	)
)
